(kicad_pcb
	(version 20241229)
	(generator "pcbnew")
	(generator_version "9.0")
	(general
		(thickness 1.599998)
		(legacy_teardrops no)
	)
	(paper "A4")
	(title_block
		(date "2023-02-12")
		(rev "1.1.5")
		(comment 9 "footprint 3 of 473 (J9), pads 92-179 of 264")
	)
	(layers
		(0 "F.Cu" signal)
		(4 "In1.Cu" power "In1.GND")
		(6 "In2.Cu" signal)
		(8 "In3.Cu" power "In3.GND")
		(10 "In4.Cu" power "In4.VCC")
		(12 "In5.Cu" signal)
		(14 "In6.Cu" power "In6.VCC")
		(2 "B.Cu" signal)
		(9 "F.Adhes" user "F.Adhesive")
		(11 "B.Adhes" user "B.Adhesive")
		(13 "F.Paste" user)
		(15 "B.Paste" user)
		(5 "F.SilkS" user "F.Silkscreen")
		(7 "B.SilkS" user "B.Silkscreen")
		(1 "F.Mask" user)
		(3 "B.Mask" user)
		(17 "Dwgs.User" user "User.Drawings")
		(19 "Cmts.User" user "User.Comments")
		(21 "Eco1.User" user "User.Eco1")
		(23 "Eco2.User" user "User.Eco2")
		(25 "Edge.Cuts" user)
		(27 "Margin" user)
		(31 "F.CrtYd" user "F.Courtyard")
		(29 "B.CrtYd" user "B.Courtyard")
		(35 "F.Fab" user)
		(33 "B.Fab" user)
	)
	(footprint "antmicro-footprints:Bus_DDR4_SODIMM_TE_2309409"
		(layer "F.Cu")
		(at 150.411328 66.671157 180)
		(descr "260 pin DDR4 SODIMM Right Angle Socket, 5.2 mm (0.205 in) Stack Height, https://www.te.com/usa-en/product-2309409-1.html")
		(property "Reference" "J9"
			(at -36.726 -13.477 180)
			(layer "F.SilkS")
			(effects
				(font
					(size 0.7 0.7)
					(thickness 0.15)
				)
				(justify left bottom)
			)
		)
		(property "Value" "Bus_DDR4_SODIMM_TE_2309409"
			(at -8.1 -7.7 180)
			(layer "F.Fab")
			(effects
				(font
					(size 0.7 0.7)
					(thickness 0.15)
				)
				(justify left bottom)
			)
		)
		(property "Description" "Memory Card Connector, DDR4, SODIMM, Cam-In Locking, 260 Contacts, Copper Alloy"
			(at 0 0 180)
			(layer "F.Fab")
			(hide yes)
			(effects
				(font
					(size 1.27 1.27)
					(thickness 0.15)
				)
			)
		)
		(property "Author" "Antmicro"
			(at 300.822656 133.342314 0)
			(layer "F.Fab")
			(hide yes)
			(effects
				(font
					(size 1 1)
					(thickness 0.15)
				)
			)
		)
		(property "License" "Apache-2.0"
			(at 300.822656 133.342314 0)
			(layer "F.Fab")
			(hide yes)
			(effects
				(font
					(size 1 1)
					(thickness 0.15)
				)
			)
		)
		(property "MPN" "2309409-1"
			(at 300.822656 133.342314 0)
			(layer "F.Fab")
			(hide yes)
			(effects
				(font
					(size 1 1)
					(thickness 0.15)
				)
			)
		)
		(property "Manufacturer" "TE Connectivity"
			(at 300.822656 133.342314 0)
			(layer "F.Fab")
			(hide yes)
			(effects
				(font
					(size 1 1)
					(thickness 0.15)
				)
			)
		)
		(sheetname "SO-DIMM")
		(sheetfile "sodimm.kicad_sch")
		(attr smd)
		(pad "90" smd rect
			(at 11.124 -3.979 180)
			(size 0.3 1.75)
			(layers "F.Cu" "F.Mask" "F.Paste")
			(net 131 "unconnected-(J9-Pad90)")
			(pinfunction "90")
			(pintype "passive+no_connect")
		)
		(pad "91" smd rect
			(at 10.874 -12.176 180)
			(size 0.3 1.75)
			(layers "F.Cu" "F.Mask" "F.Paste")
			(net 132 "unconnected-(J9-Pad91)")
			(pinfunction "91")
			(pintype "passive+no_connect")
		)
		(pad "92" smd rect
			(at 10.624 -3.979 180)
			(size 0.3 1.75)
			(layers "F.Cu" "F.Mask" "F.Paste")
			(net 133 "unconnected-(J9-Pad92)")
			(pinfunction "92")
			(pintype "passive+no_connect")
		)
		(pad "93" smd rect
			(at 10.374 -12.176 180)
			(size 0.3 1.75)
			(layers "F.Cu" "F.Mask" "F.Paste")
			(net 273 "1V1_DDR")
			(pinfunction "93")
			(pintype "passive")
		)
		(pad "94" smd rect
			(at 10.124 -3.979 180)
			(size 0.3 1.75)
			(layers "F.Cu" "F.Mask" "F.Paste")
			(net 134 "unconnected-(J9-Pad94)")
			(pinfunction "94")
			(pintype "passive+no_connect")
		)
		(pad "95" smd rect
			(at 9.874 -12.176 180)
			(size 0.3 1.75)
			(layers "F.Cu" "F.Mask" "F.Paste")
			(net 273 "1V1_DDR")
			(pinfunction "95")
			(pintype "passive")
		)
		(pad "96" smd rect
			(at 9.624 -3.979 180)
			(size 0.3 1.75)
			(layers "F.Cu" "F.Mask" "F.Paste")
			(net 135 "unconnected-(J9-Pad96)")
			(pinfunction "96")
			(pintype "passive+no_connect")
		)
		(pad "97" smd rect
			(at 9.374 -12.176 180)
			(size 0.3 1.75)
			(layers "F.Cu" "F.Mask" "F.Paste")
			(net 273 "1V1_DDR")
			(pinfunction "97")
			(pintype "passive")
		)
		(pad "98" smd rect
			(at 9.124 -3.979 180)
			(size 0.3 1.75)
			(layers "F.Cu" "F.Mask" "F.Paste")
			(net 136 "unconnected-(J9-Pad98)")
			(pinfunction "98")
			(pintype "passive+no_connect")
		)
		(pad "99" smd rect
			(at 8.874 -12.176 180)
			(size 0.3 1.75)
			(layers "F.Cu" "F.Mask" "F.Paste")
			(net 273 "1V1_DDR")
			(pinfunction "99")
			(pintype "passive")
		)
		(pad "100" smd rect
			(at 8.624 -3.979 180)
			(size 0.3 1.75)
			(layers "F.Cu" "F.Mask" "F.Paste")
			(net 137 "unconnected-(J9-Pad100)")
			(pinfunction "100")
			(pintype "passive+no_connect")
		)
		(pad "101" smd rect
			(at 8.374 -12.176 180)
			(size 0.3 1.75)
			(layers "F.Cu" "F.Mask" "F.Paste")
			(net 273 "1V1_DDR")
			(pinfunction "101")
			(pintype "passive")
		)
		(pad "102" smd rect
			(at 8.124 -3.979 180)
			(size 0.3 1.75)
			(layers "F.Cu" "F.Mask" "F.Paste")
			(net 138 "unconnected-(J9-Pad102)")
			(pinfunction "102")
			(pintype "passive+no_connect")
		)
		(pad "103" smd rect
			(at 7.874 -12.176 180)
			(size 0.3 1.75)
			(layers "F.Cu" "F.Mask" "F.Paste")
			(net 273 "1V1_DDR")
			(pinfunction "103")
			(pintype "passive")
		)
		(pad "104" smd rect
			(at 7.624 -3.979 180)
			(size 0.3 1.75)
			(layers "F.Cu" "F.Mask" "F.Paste")
			(net 139 "unconnected-(J9-Pad104)")
			(pinfunction "104")
			(pintype "passive+no_connect")
		)
		(pad "105" smd rect
			(at 7.374 -12.176 180)
			(size 0.3 1.75)
			(layers "F.Cu" "F.Mask" "F.Paste")
			(net 273 "1V1_DDR")
			(pinfunction "105")
			(pintype "passive")
		)
		(pad "106" smd rect
			(at 7.124 -3.979 180)
			(size 0.3 1.75)
			(layers "F.Cu" "F.Mask" "F.Paste")
			(net 140 "unconnected-(J9-Pad106)")
			(pinfunction "106")
			(pintype "passive+no_connect")
		)
		(pad "107" smd rect
			(at 6.874 -12.176 180)
			(size 0.3 1.75)
			(layers "F.Cu" "F.Mask" "F.Paste")
			(net 273 "1V1_DDR")
			(pinfunction "107")
			(pintype "passive")
		)
		(pad "108" smd rect
			(at 6.624 -3.979 180)
			(size 0.3 1.75)
			(layers "F.Cu" "F.Mask" "F.Paste")
			(net 141 "unconnected-(J9-Pad108)")
			(pinfunction "108")
			(pintype "passive+no_connect")
		)
		(pad "109" smd rect
			(at 6.374 -12.176 180)
			(size 0.3 1.75)
			(layers "F.Cu" "F.Mask" "F.Paste")
			(net 142 "unconnected-(J9-Pad109)")
			(pinfunction "109")
			(pintype "passive+no_connect")
		)
		(pad "110" smd rect
			(at 6.124 -3.979 180)
			(size 0.3 1.75)
			(layers "F.Cu" "F.Mask" "F.Paste")
			(net 143 "unconnected-(J9-Pad110)")
			(pinfunction "110")
			(pintype "passive+no_connect")
		)
		(pad "111" smd rect
			(at 5.874 -12.176 180)
			(size 0.3 1.75)
			(layers "F.Cu" "F.Mask" "F.Paste")
			(net 144 "unconnected-(J9-Pad111)")
			(pinfunction "111")
			(pintype "passive+no_connect")
		)
		(pad "112" smd rect
			(at 5.624 -3.979 180)
			(size 0.3 1.75)
			(layers "F.Cu" "F.Mask" "F.Paste")
			(net 145 "unconnected-(J9-Pad112)")
			(pinfunction "112")
			(pintype "passive+no_connect")
		)
		(pad "113" smd rect
			(at 5.374 -12.176 180)
			(size 0.3 1.75)
			(layers "F.Cu" "F.Mask" "F.Paste")
			(net 146 "unconnected-(J9-Pad113)")
			(pinfunction "113")
			(pintype "passive+no_connect")
		)
		(pad "114" smd rect
			(at 5.124 -3.979 180)
			(size 0.3 1.75)
			(layers "F.Cu" "F.Mask" "F.Paste")
			(net 147 "unconnected-(J9-Pad114)")
			(pinfunction "114")
			(pintype "passive+no_connect")
		)
		(pad "115" smd rect
			(at 4.874 -12.176 180)
			(size 0.3 1.75)
			(layers "F.Cu" "F.Mask" "F.Paste")
			(net 148 "unconnected-(J9-Pad115)")
			(pinfunction "115")
			(pintype "passive+no_connect")
		)
		(pad "116" smd rect
			(at 4.624 -3.979 180)
			(size 0.3 1.75)
			(layers "F.Cu" "F.Mask" "F.Paste")
			(net 641 "1V8_DDR")
			(pinfunction "116")
			(pintype "passive")
		)
		(pad "117" smd rect
			(at 4.374 -12.176 180)
			(size 0.3 1.75)
			(layers "F.Cu" "F.Mask" "F.Paste")
			(net 149 "unconnected-(J9-Pad117)")
			(pinfunction "117")
			(pintype "passive+no_connect")
		)
		(pad "118" smd rect
			(at 4.124 -3.979 180)
			(size 0.3 1.75)
			(layers "F.Cu" "F.Mask" "F.Paste")
			(net 641 "1V8_DDR")
			(pinfunction "118")
			(pintype "passive")
		)
		(pad "119" smd rect
			(at 3.874 -12.176 180)
			(size 0.3 1.75)
			(layers "F.Cu" "F.Mask" "F.Paste")
			(net 150 "unconnected-(J9-Pad119)")
			(pinfunction "119")
			(pintype "passive+no_connect")
		)
		(pad "120" smd rect
			(at 3.624 -3.979 180)
			(size 0.3 1.75)
			(layers "F.Cu" "F.Mask" "F.Paste")
			(net 641 "1V8_DDR")
			(pinfunction "120")
			(pintype "passive")
		)
		(pad "121" smd rect
			(at 3.374 -12.176 180)
			(size 0.3 1.75)
			(layers "F.Cu" "F.Mask" "F.Paste")
			(net 151 "unconnected-(J9-Pad121)")
			(pinfunction "121")
			(pintype "passive+no_connect")
		)
		(pad "122" smd rect
			(at 3.124 -3.979 180)
			(size 0.3 1.75)
			(layers "F.Cu" "F.Mask" "F.Paste")
			(net 641 "1V8_DDR")
			(pinfunction "122")
			(pintype "passive")
		)
		(pad "123" smd rect
			(at 2.874 -12.176 180)
			(size 0.3 1.75)
			(layers "F.Cu" "F.Mask" "F.Paste")
			(net 152 "unconnected-(J9-Pad123)")
			(pinfunction "123")
			(pintype "passive+no_connect")
		)
		(pad "124" smd rect
			(at 2.624 -3.979 180)
			(size 0.3 1.75)
			(layers "F.Cu" "F.Mask" "F.Paste")
			(net 641 "1V8_DDR")
			(pinfunction "124")
			(pintype "passive")
		)
		(pad "125" smd rect
			(at 2.374 -12.176 180)
			(size 0.3 1.75)
			(layers "F.Cu" "F.Mask" "F.Paste")
			(net 153 "unconnected-(J9-Pad125)")
			(pinfunction "125")
			(pintype "passive+no_connect")
		)
		(pad "126" smd rect
			(at 2.124 -3.979 180)
			(size 0.3 1.75)
			(layers "F.Cu" "F.Mask" "F.Paste")
			(net 66 "VDDQ")
			(pinfunction "126")
			(pintype "passive")
		)
		(pad "127" smd rect
			(at 1.874 -12.176 180)
			(size 0.3 1.75)
			(layers "F.Cu" "F.Mask" "F.Paste")
			(net 487 "IO_U12")
			(pinfunction "127")
			(pintype "passive")
		)
		(pad "128" smd rect
			(at 1.624 -3.979 180)
			(size 0.3 1.75)
			(layers "F.Cu" "F.Mask" "F.Paste")
			(net 66 "VDDQ")
			(pinfunction "128")
			(pintype "passive")
		)
		(pad "129" smd rect
			(at 1.374 -12.176 180)
			(size 0.3 1.75)
			(layers "F.Cu" "F.Mask" "F.Paste")
			(net 486 "IO_V12")
			(pinfunction "129")
			(pintype "passive")
		)
		(pad "130" smd rect
			(at 1.124 -3.979 180)
			(size 0.3 1.75)
			(layers "F.Cu" "F.Mask" "F.Paste")
			(net 66 "VDDQ")
			(pinfunction "130")
			(pintype "passive")
		)
		(pad "131" smd rect
			(at 0.874 -12.176 180)
			(size 0.3 1.75)
			(layers "F.Cu" "F.Mask" "F.Paste")
			(net 485 "IO_W12")
			(pinfunction "131")
			(pintype "passive")
		)
		(pad "132" smd rect
			(at 0.624 -3.979 180)
			(size 0.3 1.75)
			(layers "F.Cu" "F.Mask" "F.Paste")
			(net 154 "unconnected-(J9-Pad132)")
			(pinfunction "132")
			(pintype "passive+no_connect")
		)
		(pad "133" smd rect
			(at 0.374 -12.176 180)
			(size 0.3 1.75)
			(layers "F.Cu" "F.Mask" "F.Paste")
			(net 484 "IO_Y12")
			(pinfunction "133")
			(pintype "passive")
		)
		(pad "134" smd rect
			(at 0.124 -3.979 180)
			(size 0.3 1.75)
			(layers "F.Cu" "F.Mask" "F.Paste")
			(net 155 "unconnected-(J9-Pad134)")
			(pinfunction "134")
			(pintype "passive+no_connect")
		)
		(pad "135" smd rect
			(at -0.125 -12.176 180)
			(size 0.3 1.75)
			(layers "F.Cu" "F.Mask" "F.Paste")
			(net 483 "IO_W11")
			(pinfunction "135")
			(pintype "passive")
		)
		(pad "136" smd rect
			(at -0.375 -3.979 180)
			(size 0.3 1.75)
			(layers "F.Cu" "F.Mask" "F.Paste")
			(net 156 "unconnected-(J9-Pad136)")
			(pinfunction "136")
			(pintype "passive+no_connect")
		)
		(pad "137" smd rect
			(at -0.625 -12.176 180)
			(size 0.3 1.75)
			(layers "F.Cu" "F.Mask" "F.Paste")
			(net 482 "IO_Y11")
			(pinfunction "137")
			(pintype "passive")
		)
		(pad "138" smd rect
			(at -0.875 -3.979 180)
			(size 0.3 1.75)
			(layers "F.Cu" "F.Mask" "F.Paste")
			(net 157 "unconnected-(J9-Pad138)")
			(pinfunction "138")
			(pintype "passive+no_connect")
		)
		(pad "139" smd rect
			(at -1.125 -12.176 180)
			(size 0.3 1.75)
			(layers "F.Cu" "F.Mask" "F.Paste")
			(net 481 "IO_AA11")
			(pinfunction "139")
			(pintype "passive")
		)
		(pad "140" smd rect
			(at -1.375 -3.979 180)
			(size 0.3 1.75)
			(layers "F.Cu" "F.Mask" "F.Paste")
			(net 158 "unconnected-(J9-Pad140)")
			(pinfunction "140")
			(pintype "passive+no_connect")
		)
		(pad "141" smd rect
			(at -1.625 -12.176 180)
			(size 0.3 1.75)
			(layers "F.Cu" "F.Mask" "F.Paste")
			(net 479 "IO_AB11")
			(pinfunction "141")
			(pintype "passive")
		)
		(pad "142" smd rect
			(at -1.875 -3.979 180)
			(size 0.3 1.75)
			(layers "F.Cu" "F.Mask" "F.Paste")
			(net 159 "unconnected-(J9-Pad142)")
			(pinfunction "142")
			(pintype "passive+no_connect")
		)
		(pad "143" smd rect
			(at -2.125 -12.176 180)
			(size 0.3 1.75)
			(layers "F.Cu" "F.Mask" "F.Paste")
			(net 480 "IO_AB10")
			(pinfunction "143")
			(pintype "passive")
		)
		(pad "144" smd rect
			(at -2.375 -3.979 180)
			(size 0.3 1.75)
			(layers "F.Cu" "F.Mask" "F.Paste")
			(net 160 "unconnected-(J9-Pad144)")
			(pinfunction "144")
			(pintype "passive+no_connect")
		)
		(pad "145" smd rect
			(at -4.625 -12.176 180)
			(size 0.3 1.75)
			(layers "F.Cu" "F.Mask" "F.Paste")
			(net 161 "unconnected-(J9-Pad145)")
			(pinfunction "145")
			(pintype "passive+no_connect")
		)
		(pad "146" smd rect
			(at -4.875 -3.979 180)
			(size 0.3 1.75)
			(layers "F.Cu" "F.Mask" "F.Paste")
			(net 162 "unconnected-(J9-Pad146)")
			(pinfunction "146")
			(pintype "passive+no_connect")
		)
		(pad "147" smd rect
			(at -5.125 -12.176 180)
			(size 0.3 1.75)
			(layers "F.Cu" "F.Mask" "F.Paste")
			(net 163 "unconnected-(J9-Pad147)")
			(pinfunction "147")
			(pintype "passive+no_connect")
		)
		(pad "148" smd rect
			(at -5.375 -3.979 180)
			(size 0.3 1.75)
			(layers "F.Cu" "F.Mask" "F.Paste")
			(net 164 "unconnected-(J9-Pad148)")
			(pinfunction "148")
			(pintype "passive+no_connect")
		)
		(pad "149" smd rect
			(at -5.625 -12.176 180)
			(size 0.3 1.75)
			(layers "F.Cu" "F.Mask" "F.Paste")
			(net 165 "unconnected-(J9-Pad149)")
			(pinfunction "149")
			(pintype "passive+no_connect")
		)
		(pad "150" smd rect
			(at -5.875 -3.979 180)
			(size 0.3 1.75)
			(layers "F.Cu" "F.Mask" "F.Paste")
			(net 166 "unconnected-(J9-Pad150)")
			(pinfunction "150")
			(pintype "passive+no_connect")
		)
		(pad "151" smd rect
			(at -6.125 -12.176 180)
			(size 0.3 1.75)
			(layers "F.Cu" "F.Mask" "F.Paste")
			(net 167 "unconnected-(J9-Pad151)")
			(pinfunction "151")
			(pintype "passive+no_connect")
		)
		(pad "152" smd rect
			(at -6.375 -3.979 180)
			(size 0.3 1.75)
			(layers "F.Cu" "F.Mask" "F.Paste")
			(net 168 "unconnected-(J9-Pad152)")
			(pinfunction "152")
			(pintype "passive+no_connect")
		)
		(pad "153" smd rect
			(at -6.625 -12.176 180)
			(size 0.3 1.75)
			(layers "F.Cu" "F.Mask" "F.Paste")
			(net 169 "unconnected-(J9-Pad153)")
			(pinfunction "153")
			(pintype "passive+no_connect")
		)
		(pad "154" smd rect
			(at -6.875 -3.979 180)
			(size 0.3 1.75)
			(layers "F.Cu" "F.Mask" "F.Paste")
			(net 5 "GND")
			(pinfunction "154")
			(pintype "passive")
		)
		(pad "155" smd rect
			(at -7.125 -12.176 180)
			(size 0.3 1.75)
			(layers "F.Cu" "F.Mask" "F.Paste")
			(net 170 "unconnected-(J9-Pad155)")
			(pinfunction "155")
			(pintype "passive+no_connect")
		)
		(pad "156" smd rect
			(at -7.375 -3.979 180)
			(size 0.3 1.75)
			(layers "F.Cu" "F.Mask" "F.Paste")
			(net 68 "CA5_A")
			(pinfunction "156")
			(pintype "passive")
		)
		(pad "157" smd rect
			(at -7.625 -12.176 180)
			(size 0.3 1.75)
			(layers "F.Cu" "F.Mask" "F.Paste")
			(net 171 "unconnected-(J9-Pad157)")
			(pinfunction "157")
			(pintype "passive+no_connect")
		)
		(pad "158" smd rect
			(at -7.875 -3.979 180)
			(size 0.3 1.75)
			(layers "F.Cu" "F.Mask" "F.Paste")
			(net 69 "CA4_A")
			(pinfunction "158")
			(pintype "passive")
		)
		(pad "159" smd rect
			(at -8.125 -12.176 180)
			(size 0.3 1.75)
			(layers "F.Cu" "F.Mask" "F.Paste")
			(net 172 "unconnected-(J9-Pad159)")
			(pinfunction "159")
			(pintype "passive+no_connect")
		)
		(pad "160" smd rect
			(at -8.375 -3.979 180)
			(size 0.3 1.75)
			(layers "F.Cu" "F.Mask" "F.Paste")
			(net 70 "CA3_A")
			(pinfunction "160")
			(pintype "passive")
		)
		(pad "161" smd rect
			(at -8.625 -12.176 180)
			(size 0.3 1.75)
			(layers "F.Cu" "F.Mask" "F.Paste")
			(net 5 "GND")
			(pinfunction "161")
			(pintype "passive")
		)
		(pad "162" smd rect
			(at -8.875 -3.979 180)
			(size 0.3 1.75)
			(layers "F.Cu" "F.Mask" "F.Paste")
			(net 71 "CA2_A")
			(pinfunction "162")
			(pintype "passive")
		)
		(pad "163" smd rect
			(at -9.125 -12.176 180)
			(size 0.3 1.75)
			(layers "F.Cu" "F.Mask" "F.Paste")
			(net 332 "DQ11_A")
			(pinfunction "163")
			(pintype "passive")
		)
		(pad "164" smd rect
			(at -9.375 -3.979 180)
			(size 0.3 1.75)
			(layers "F.Cu" "F.Mask" "F.Paste")
			(net 352 "CK_A_N")
			(pinfunction "164")
			(pintype "passive")
		)
		(pad "165" smd rect
			(at -9.625 -12.176 180)
			(size 0.3 1.75)
			(layers "F.Cu" "F.Mask" "F.Paste")
			(net 333 "DQ10_A")
			(pinfunction "165")
			(pintype "passive")
		)
		(pad "166" smd rect
			(at -9.875 -3.979 180)
			(size 0.3 1.75)
			(layers "F.Cu" "F.Mask" "F.Paste")
			(net 353 "CK_A_P")
			(pinfunction "166")
			(pintype "passive")
		)
		(pad "167" smd rect
			(at -10.125 -12.176 180)
			(size 0.3 1.75)
			(layers "F.Cu" "F.Mask" "F.Paste")
			(net 334 "DQ09_A")
			(pinfunction "167")
			(pintype "passive")
		)
		(pad "168" smd rect
			(at -10.375 -3.979 180)
			(size 0.3 1.75)
			(layers "F.Cu" "F.Mask" "F.Paste")
			(net 5 "GND")
			(pinfunction "168")
			(pintype "passive")
		)
		(pad "169" smd rect
			(at -10.625 -12.176 180)
			(size 0.3 1.75)
			(layers "F.Cu" "F.Mask" "F.Paste")
			(net 335 "DQ08_A")
			(pinfunction "169")
			(pintype "passive")
		)
		(pad "170" smd rect
			(at -10.875 -3.979 180)
			(size 0.3 1.75)
			(layers "F.Cu" "F.Mask" "F.Paste")
			(net 398 "IO_W4")
			(pinfunction "170")
			(pintype "passive")
		)
		(pad "171" smd rect
			(at -11.125 -12.176 180)
			(size 0.3 1.75)
			(layers "F.Cu" "F.Mask" "F.Paste")
			(net 336 "DMI_1A")
			(pinfunction "171")
			(pintype "passive")
		)
		(pad "172" smd rect
			(at -11.375 -3.979 180)
			(size 0.3 1.75)
			(layers "F.Cu" "F.Mask" "F.Paste")
			(net 403 "IO_V3")
			(pinfunction "172")
			(pintype "passive")
		)
		(pad "173" smd rect
			(at -11.625 -12.176 180)
			(size 0.3 1.75)
			(layers "F.Cu" "F.Mask" "F.Paste")
			(net 648 "DQ_S1_N")
			(pinfunction "173")
			(pintype "passive")
		)
		(pad "174" smd rect
			(at -11.875 -3.979 180)
			(size 0.3 1.75)
			(layers "F.Cu" "F.Mask" "F.Paste")
			(net 399 "IO_V4")
			(pinfunction "174")
			(pintype "passive")
		)
		(pad "175" smd rect
			(at -12.125 -12.176 180)
			(size 0.3 1.75)
			(layers "F.Cu" "F.Mask" "F.Paste")
			(net 649 "DQ_S1_P")
			(pinfunction "175")
			(pintype "passive")
		)
		(pad "176" smd rect
			(at -12.375 -3.979 180)
			(size 0.3 1.75)
			(layers "F.Cu" "F.Mask" "F.Paste")
			(net 404 "IO_U3")
			(pinfunction "176")
			(pintype "passive")
		)
		(pad "177" smd rect
			(at -12.625 -12.176 180)
			(size 0.3 1.75)
			(layers "F.Cu" "F.Mask" "F.Paste")
			(net 5 "GND")
			(pinfunction "177")
			(pintype "passive")
		)
	)
)
